(kicad_pcb
	(version 20241229)
	(generator "pcbnew")
	(generator_version "9.0")
	(general
		(thickness 1.62)
		(legacy_teardrops no)
	)
	(paper "A3")
	(title_block
		(title "COM Express 7 Baseboard")
		(date "2025-02-04")
		(rev "1.1.2")
		(company "Antmicro Ltd")
		(comment 1 "www.antmicro.com")
		(comment 9 "footprints 660-665 of 802")
	)
	(layers
		(0 "F.Cu" signal)
		(4 "In1.Cu" signal)
		(6 "In2.Cu" signal)
		(8 "In3.Cu" signal)
		(10 "In4.Cu" signal)
		(12 "In5.Cu" signal)
		(14 "In6.Cu" signal)
		(2 "B.Cu" signal)
		(9 "F.Adhes" user "F.Adhesive")
		(11 "B.Adhes" user "B.Adhesive")
		(13 "F.Paste" user)
		(15 "B.Paste" user)
		(5 "F.SilkS" user "F.Silkscreen")
		(7 "B.SilkS" user "B.Silkscreen")
		(1 "F.Mask" user)
		(3 "B.Mask" user)
		(17 "Dwgs.User" user "User.Drawings")
		(19 "Cmts.User" user "User.Comments")
		(21 "Eco1.User" user "User.Eco1")
		(23 "Eco2.User" user "User.Eco2")
		(25 "Edge.Cuts" user)
		(27 "Margin" user)
		(31 "F.CrtYd" user "F.Courtyard")
		(29 "B.CrtYd" user "B.Courtyard")
		(35 "F.Fab" user)
		(33 "B.Fab" user)
	)
	(footprint "antmicro-footprints:R_0402_1005Metric"
		(layer "B.Cu")
		(at 139.74 139.36)
		(descr "Resistor SMD 0402")
		(tags "resistor SMD 0402")
		(property "Reference" "R298"
			(at -3.64 0.75 0)
			(layer "B.SilkS")
			(effects
				(font
					(size 0.7 0.7)
					(thickness 0.15)
				)
				(justify right bottom mirror)
			)
		)
		(property "Value" "R_10k_0402"
			(at -1.011843 -1.772047 0)
			(layer "B.Fab")
			(effects
				(font
					(size 0.7 0.7)
					(thickness 0.15)
				)
				(justify right bottom mirror)
			)
		)
		(property "Datasheet" "https://www.bourns.com/docs/product-datasheets/cr.pdf"
			(at 0 0 0)
			(layer "F.Fab")
			(hide yes)
			(effects
				(font
					(size 1.27 1.27)
					(thickness 0.15)
				)
			)
		)
		(property "Author" "Antmicro"
			(at 0 0 0)
			(layer "B.Fab")
			(hide yes)
			(effects
				(font
					(size 1 1)
					(thickness 0.15)
				)
				(justify mirror)
			)
		)
		(property "License" "Apache-2.0"
			(at 0 0 0)
			(layer "B.Fab")
			(hide yes)
			(effects
				(font
					(size 1 1)
					(thickness 0.15)
				)
				(justify mirror)
			)
		)
		(property "MPN" "CR0402-FX-1002GLF"
			(at 0 0 0)
			(layer "B.Fab")
			(hide yes)
			(effects
				(font
					(size 1 1)
					(thickness 0.15)
				)
				(justify mirror)
			)
		)
		(property "Manufacturer" "Bourns"
			(at 0 0 0)
			(layer "B.Fab")
			(hide yes)
			(effects
				(font
					(size 1 1)
					(thickness 0.15)
				)
				(justify mirror)
			)
		)
		(property "Public" "False"
			(at 0 0 0)
			(layer "B.Fab")
			(hide yes)
			(effects
				(font
					(size 1 1)
					(thickness 0.15)
				)
				(justify mirror)
			)
		)
		(property "Tolerance" "1%"
			(at 0 0 0)
			(layer "B.Fab")
			(hide yes)
			(effects
				(font
					(size 1 1)
					(thickness 0.15)
				)
				(justify mirror)
			)
		)
		(property "Val" "10k"
			(at 0 0 0)
			(layer "B.Fab")
			(hide yes)
			(effects
				(font
					(size 1 1)
					(thickness 0.15)
				)
				(justify mirror)
			)
		)
		(sheetname "KR to SFI #2")
		(sheetfile "kr_sfi.kicad_sch")
		(attr smd)
		(fp_rect
			(start -0.925 0.47)
			(end 0.925 -0.47)
			(stroke
				(width 0.05)
				(type default)
			)
			(fill no)
			(layer "B.CrtYd")
		)
		(fp_rect
			(start -0.5 0.25)
			(end 0.5 -0.25)
			(stroke
				(width 0.15)
				(type solid)
			)
			(fill no)
			(layer "B.Fab")
		)
		(pad "1" smd roundrect
			(at -0.48 0)
			(size 0.59 0.64)
			(layers "B.Cu" "B.Mask" "B.Paste")
			(roundrect_rratio 0.25)
			(net 678 "Net-(U45A-~{PDTRXA})")
			(pintype "passive")
			(teardrops
				(best_length_ratio 0.2)
				(max_length 1)
				(best_width_ratio 0.9)
				(max_width 2)
				(curved_edges yes)
				(filter_ratio 0.9)
				(enabled yes)
				(allow_two_segments yes)
				(prefer_zone_connections yes)
			)
		)
		(pad "2" smd roundrect
			(at 0.48 0)
			(size 0.59 0.64)
			(layers "B.Cu" "B.Mask" "B.Paste")
			(roundrect_rratio 0.25)
			(net 78 "+1V8")
			(pintype "passive")
			(teardrops
				(best_length_ratio 0.2)
				(max_length 1)
				(best_width_ratio 0.9)
				(max_width 2)
				(curved_edges yes)
				(filter_ratio 0.9)
				(enabled yes)
				(allow_two_segments yes)
				(prefer_zone_connections yes)
			)
		)
	)
	(footprint "antmicro-footprints:R_0402_1005Metric"
		(layer "B.Cu")
		(at 123.4 110.81 180)
		(descr "Resistor SMD 0402")
		(tags "resistor SMD 0402")
		(property "Reference" "R6"
			(at -2.35 -0.45 0)
			(layer "B.SilkS")
			(effects
				(font
					(size 0.7 0.7)
					(thickness 0.15)
				)
				(justify left bottom mirror)
			)
		)
		(property "Value" "R_0R_0402"
			(at -1.011843 -1.772047 0)
			(layer "B.Fab")
			(effects
				(font
					(size 0.7 0.7)
					(thickness 0.15)
				)
				(justify left bottom mirror)
			)
		)
		(property "Datasheet" "https://industrial.panasonic.com/cdbs/www-data/pdf/RDA0000/AOA0000C301.pdf"
			(at 0 0 180)
			(layer "F.Fab")
			(hide yes)
			(effects
				(font
					(size 1.27 1.27)
					(thickness 0.15)
				)
			)
		)
		(property "Author" "Antmicro"
			(at 246.8 221.62 0)
			(layer "B.Fab")
			(hide yes)
			(effects
				(font
					(size 1 1)
					(thickness 0.15)
				)
				(justify mirror)
			)
		)
		(property "Current" "1A"
			(at 246.8 221.62 0)
			(layer "B.Fab")
			(hide yes)
			(effects
				(font
					(size 1 1)
					(thickness 0.15)
				)
				(justify mirror)
			)
		)
		(property "License" "Apache-2.0"
			(at 246.8 221.62 0)
			(layer "B.Fab")
			(hide yes)
			(effects
				(font
					(size 1 1)
					(thickness 0.15)
				)
				(justify mirror)
			)
		)
		(property "MPN" "ERJ2GE0R00X"
			(at 246.8 221.62 0)
			(layer "B.Fab")
			(hide yes)
			(effects
				(font
					(size 1 1)
					(thickness 0.15)
				)
				(justify mirror)
			)
		)
		(property "Manufacturer" "Panasonic"
			(at 246.8 221.62 0)
			(layer "B.Fab")
			(hide yes)
			(effects
				(font
					(size 1 1)
					(thickness 0.15)
				)
				(justify mirror)
			)
		)
		(property "Public" "False"
			(at 246.8 221.62 0)
			(layer "B.Fab")
			(hide yes)
			(effects
				(font
					(size 1 1)
					(thickness 0.15)
				)
				(justify mirror)
			)
		)
		(property "Tolerance" ""
			(at 246.8 221.62 0)
			(layer "B.Fab")
			(hide yes)
			(effects
				(font
					(size 1 1)
					(thickness 0.15)
				)
				(justify mirror)
			)
		)
		(property "Val" "0R"
			(at 246.8 221.62 0)
			(layer "B.Fab")
			(hide yes)
			(effects
				(font
					(size 1 1)
					(thickness 0.15)
				)
				(justify mirror)
			)
		)
		(sheetname "2xUSB3.0+RJ45")
		(sheetfile "usb3+rj45.kicad_sch")
		(attr smd dnp)
		(fp_rect
			(start -0.925 0.47)
			(end 0.925 -0.47)
			(stroke
				(width 0.05)
				(type default)
			)
			(fill no)
			(layer "B.CrtYd")
		)
		(fp_rect
			(start -0.5 0.25)
			(end 0.5 -0.25)
			(stroke
				(width 0.15)
				(type solid)
			)
			(fill no)
			(layer "B.Fab")
		)
		(pad "1" smd roundrect
			(at -0.48 0 180)
			(size 0.59 0.64)
			(layers "B.Cu" "B.Mask" "B.Paste")
			(roundrect_rratio 0.25)
			(net 291 "/2xUSB3.0+RJ45/~{GBE0_LINK}")
			(pintype "passive")
			(teardrops
				(best_length_ratio 0.2)
				(max_length 1)
				(best_width_ratio 0.9)
				(max_width 2)
				(curved_edges yes)
				(filter_ratio 0.9)
				(enabled yes)
				(allow_two_segments yes)
				(prefer_zone_connections yes)
			)
		)
		(pad "2" smd roundrect
			(at 0.48 0 180)
			(size 0.59 0.64)
			(layers "B.Cu" "B.Mask" "B.Paste")
			(roundrect_rratio 0.25)
			(net 156 "Net-(J1A-LED_D3)")
			(pintype "passive")
			(teardrops
				(best_length_ratio 0.2)
				(max_length 1)
				(best_width_ratio 0.9)
				(max_width 2)
				(curved_edges yes)
				(filter_ratio 0.9)
				(enabled yes)
				(allow_two_segments yes)
				(prefer_zone_connections yes)
			)
		)
	)
	(footprint "antmicro-footprints:R_0402_1005Metric"
		(layer "B.Cu")
		(at 157.9 140.36)
		(descr "Resistor SMD 0402")
		(tags "resistor SMD 0402")
		(property "Reference" "R252"
			(at 0.85 0.45 0)
			(layer "B.SilkS")
			(effects
				(font
					(size 0.7 0.7)
					(thickness 0.15)
				)
				(justify right bottom mirror)
			)
		)
		(property "Value" "R_10k_0402"
			(at -1.011843 -1.772047 0)
			(layer "B.Fab")
			(effects
				(font
					(size 0.7 0.7)
					(thickness 0.15)
				)
				(justify right bottom mirror)
			)
		)
		(property "Datasheet" "https://www.bourns.com/docs/product-datasheets/cr.pdf"
			(at 0 0 0)
			(layer "F.Fab")
			(hide yes)
			(effects
				(font
					(size 1.27 1.27)
					(thickness 0.15)
				)
			)
		)
		(property "Author" "Antmicro"
			(at 0 0 0)
			(layer "B.Fab")
			(hide yes)
			(effects
				(font
					(size 1 1)
					(thickness 0.15)
				)
				(justify mirror)
			)
		)
		(property "License" "Apache-2.0"
			(at 0 0 0)
			(layer "B.Fab")
			(hide yes)
			(effects
				(font
					(size 1 1)
					(thickness 0.15)
				)
				(justify mirror)
			)
		)
		(property "MPN" "CR0402-FX-1002GLF"
			(at 0 0 0)
			(layer "B.Fab")
			(hide yes)
			(effects
				(font
					(size 1 1)
					(thickness 0.15)
				)
				(justify mirror)
			)
		)
		(property "Manufacturer" "Bourns"
			(at 0 0 0)
			(layer "B.Fab")
			(hide yes)
			(effects
				(font
					(size 1 1)
					(thickness 0.15)
				)
				(justify mirror)
			)
		)
		(property "Public" "False"
			(at 0 0 0)
			(layer "B.Fab")
			(hide yes)
			(effects
				(font
					(size 1 1)
					(thickness 0.15)
				)
				(justify mirror)
			)
		)
		(property "Tolerance" "1%"
			(at 0 0 0)
			(layer "B.Fab")
			(hide yes)
			(effects
				(font
					(size 1 1)
					(thickness 0.15)
				)
				(justify mirror)
			)
		)
		(property "Val" "10k"
			(at 0 0 0)
			(layer "B.Fab")
			(hide yes)
			(effects
				(font
					(size 1 1)
					(thickness 0.15)
				)
				(justify mirror)
			)
		)
		(sheetname "KR to SFI #1")
		(sheetfile "kr_sfi.kicad_sch")
		(attr smd dnp)
		(fp_rect
			(start -0.925 0.47)
			(end 0.925 -0.47)
			(stroke
				(width 0.05)
				(type default)
			)
			(fill no)
			(layer "B.CrtYd")
		)
		(fp_rect
			(start -0.5 0.25)
			(end 0.5 -0.25)
			(stroke
				(width 0.15)
				(type solid)
			)
			(fill no)
			(layer "B.Fab")
		)
		(pad "1" smd roundrect
			(at -0.48 0)
			(size 0.59 0.64)
			(layers "B.Cu" "B.Mask" "B.Paste")
			(roundrect_rratio 0.25)
			(net 652 "/2xSFP+/KR to SFI #1/PRBSEN")
			(pintype "passive")
			(teardrops
				(best_length_ratio 0.2)
				(max_length 1)
				(best_width_ratio 0.9)
				(max_width 2)
				(curved_edges yes)
				(filter_ratio 0.9)
				(enabled yes)
				(allow_two_segments yes)
				(prefer_zone_connections yes)
			)
		)
		(pad "2" smd roundrect
			(at 0.48 0)
			(size 0.59 0.64)
			(layers "B.Cu" "B.Mask" "B.Paste")
			(roundrect_rratio 0.25)
			(net 78 "+1V8")
			(pintype "passive")
			(teardrops
				(best_length_ratio 0.2)
				(max_length 1)
				(best_width_ratio 0.9)
				(max_width 2)
				(curved_edges yes)
				(filter_ratio 0.9)
				(enabled yes)
				(allow_two_segments yes)
				(prefer_zone_connections yes)
			)
		)
	)
	(footprint "antmicro-footprints:TP_SMD_0.75mm"
		(layer "B.Cu")
		(at 194.25 163.325)
		(property "Reference" "TP16"
			(at -0.25 -0.825 90)
			(layer "B.SilkS")
			(effects
				(font
					(size 0.7 0.7)
					(thickness 0.15)
				)
				(justify right top mirror)
			)
		)
		(property "Value" "TP_0.75mm_SMD"
			(at 3.225 -53.865 0)
			(layer "B.Fab")
			(hide yes)
			(effects
				(font
					(size 0.7 0.7)
					(thickness 0.15)
				)
				(justify right top mirror)
			)
		)
		(property "Author" "Antmicro"
			(at 418.6 313.02 0)
			(layer "B.Fab")
			(hide yes)
			(effects
				(font
					(size 1 1)
					(thickness 0.15)
				)
				(justify mirror)
			)
		)
		(property "License" "Apache-2.0"
			(at 418.6 313.02 0)
			(layer "B.Fab")
			(hide yes)
			(effects
				(font
					(size 1 1)
					(thickness 0.15)
				)
				(justify mirror)
			)
		)
		(property "MPN" ""
			(at 418.6 313.02 0)
			(layer "B.Fab")
			(hide yes)
			(effects
				(font
					(size 1 1)
					(thickness 0.15)
				)
				(justify mirror)
			)
		)
		(property "Manufacturer" ""
			(at 418.6 313.02 0)
			(layer "B.Fab")
			(hide yes)
			(effects
				(font
					(size 1 1)
					(thickness 0.15)
				)
				(justify mirror)
			)
		)
		(property "Public" "False"
			(at 418.6 313.02 0)
			(layer "B.Fab")
			(hide yes)
			(effects
				(font
					(size 1 1)
					(thickness 0.15)
				)
				(justify mirror)
			)
		)
		(sheetname "Com Express 7 Interfaces")
		(sheetfile "com_express_7_interfaces.kicad_sch")
		(attr exclude_from_pos_files exclude_from_bom)
		(fp_circle
			(center 0 0)
			(end 0.475 0)
			(stroke
				(width 0.05)
				(type default)
			)
			(fill no)
			(layer "B.CrtYd")
		)
		(pad "1" smd circle
			(at 0 0)
			(size 0.75 0.75)
			(layers "B.Cu" "B.Mask")
			(net 380 "Net-(J12G-USB0_HOST_PRSNT)")
			(pinfunction "1")
			(pintype "passive")
			(teardrops
				(best_length_ratio 0.4)
				(max_length 1)
				(best_width_ratio 0.9)
				(max_width 2)
				(curved_edges yes)
				(filter_ratio 0.9)
				(enabled yes)
				(allow_two_segments yes)
				(prefer_zone_connections yes)
			)
		)
	)
	(footprint "antmicro-footprints:TP_SMD_0.75mm"
		(layer "B.Cu")
		(at 174 163.85)
		(property "Reference" "TP25"
			(at -0.5 -0.65 90)
			(layer "B.SilkS")
			(effects
				(font
					(size 0.7 0.7)
					(thickness 0.15)
				)
				(justify right top mirror)
			)
		)
		(property "Value" "TP_0.75mm_SMD"
			(at 3.225 -53.865 0)
			(layer "B.Fab")
			(hide yes)
			(effects
				(font
					(size 0.7 0.7)
					(thickness 0.15)
				)
				(justify right top mirror)
			)
		)
		(property "Author" "Antmicro"
			(at 458.4 306.119999 0)
			(layer "B.Fab")
			(hide yes)
			(effects
				(font
					(size 1 1)
					(thickness 0.15)
				)
				(justify mirror)
			)
		)
		(property "License" "Apache-2.0"
			(at 458.4 306.119999 0)
			(layer "B.Fab")
			(hide yes)
			(effects
				(font
					(size 1 1)
					(thickness 0.15)
				)
				(justify mirror)
			)
		)
		(property "MPN" ""
			(at 458.4 306.119999 0)
			(layer "B.Fab")
			(hide yes)
			(effects
				(font
					(size 1 1)
					(thickness 0.15)
				)
				(justify mirror)
			)
		)
		(property "Manufacturer" ""
			(at 458.4 306.119999 0)
			(layer "B.Fab")
			(hide yes)
			(effects
				(font
					(size 1 1)
					(thickness 0.15)
				)
				(justify mirror)
			)
		)
		(property "Public" "False"
			(at 458.4 306.119999 0)
			(layer "B.Fab")
			(hide yes)
			(effects
				(font
					(size 1 1)
					(thickness 0.15)
				)
				(justify mirror)
			)
		)
		(sheetname "Com Express 7 MGMT")
		(sheetfile "com_express_7_mgmt.kicad_sch")
		(attr exclude_from_pos_files exclude_from_bom)
		(fp_circle
			(center 0 0)
			(end 0.475 0)
			(stroke
				(width 0.05)
				(type default)
			)
			(fill no)
			(layer "B.CrtYd")
		)
		(pad "1" smd circle
			(at 0 0)
			(size 0.75 0.75)
			(layers "B.Cu" "B.Mask")
			(net 349 "Net-(J12D-LPC_AD0{slash}ESPI_IO_0)")
			(pinfunction "1")
			(pintype "passive")
			(teardrops
				(best_length_ratio 0.4)
				(max_length 1)
				(best_width_ratio 0.9)
				(max_width 2)
				(curved_edges yes)
				(filter_ratio 0.9)
				(enabled yes)
				(allow_two_segments yes)
				(prefer_zone_connections yes)
			)
		)
	)
	(footprint "antmicro-footprints:C_0402_1005Metric"
		(layer "B.Cu")
		(at 311.274999 106.15 -90)
		(descr "Capacitor SMD 0402")
		(tags "capacitor SMD 0402")
		(property "Reference" "C45"
			(at 0.81 -0.475001 90)
			(layer "B.SilkS")
			(effects
				(font
					(size 0.7 0.7)
					(thickness 0.15)
				)
				(justify left bottom mirror)
			)
		)
		(property "Value" "C_1u_0402"
			(at -1.022927 -2.155213 90)
			(layer "B.Fab")
			(effects
				(font
					(size 0.7 0.7)
					(thickness 0.15)
				)
				(justify left bottom mirror)
			)
		)
		(property "Datasheet" "https://product.tdk.com/en/search/capacitor/ceramic/mlcc/info?part_no=C1005X6S1A105K050BC"
			(at 0 0 270)
			(layer "F.Fab")
			(hide yes)
			(effects
				(font
					(size 1.27 1.27)
					(thickness 0.15)
				)
			)
		)
		(property "Author" "Antmicro"
			(at 205.124999 417.424999 0)
			(layer "B.Fab")
			(hide yes)
			(effects
				(font
					(size 1 1)
					(thickness 0.15)
				)
				(justify mirror)
			)
		)
		(property "Dielectric" ""
			(at 205.124999 417.424999 0)
			(layer "B.Fab")
			(hide yes)
			(effects
				(font
					(size 1 1)
					(thickness 0.15)
				)
				(justify mirror)
			)
		)
		(property "License" "Apache-2.0"
			(at 205.124999 417.424999 0)
			(layer "B.Fab")
			(hide yes)
			(effects
				(font
					(size 1 1)
					(thickness 0.15)
				)
				(justify mirror)
			)
		)
		(property "MPN" "C1005X6S1A105K050BC"
			(at 205.124999 417.424999 0)
			(layer "B.Fab")
			(hide yes)
			(effects
				(font
					(size 1 1)
					(thickness 0.15)
				)
				(justify mirror)
			)
		)
		(property "Manufacturer" "TDK"
			(at 205.124999 417.424999 0)
			(layer "B.Fab")
			(hide yes)
			(effects
				(font
					(size 1 1)
					(thickness 0.15)
				)
				(justify mirror)
			)
		)
		(property "Public" "False"
			(at 205.124999 417.424999 0)
			(layer "B.Fab")
			(hide yes)
			(effects
				(font
					(size 1 1)
					(thickness 0.15)
				)
				(justify mirror)
			)
		)
		(property "Val" "1u"
			(at 205.124999 417.424999 0)
			(layer "B.Fab")
			(hide yes)
			(effects
				(font
					(size 1 1)
					(thickness 0.15)
				)
				(justify mirror)
			)
		)
		(property "Voltage" ""
			(at 205.124999 417.424999 0)
			(layer "B.Fab")
			(hide yes)
			(effects
				(font
					(size 1 1)
					(thickness 0.15)
				)
				(justify mirror)
			)
		)
		(sheetname "Power")
		(sheetfile "power.kicad_sch")
		(attr smd)
		(fp_rect
			(start -0.925 0.47)
			(end 0.925 -0.47)
			(stroke
				(width 0.05)
				(type default)
			)
			(fill no)
			(layer "B.CrtYd")
		)
		(fp_line
			(start -0.494 0.25)
			(end -0.494 -0.248)
			(stroke
				(width 0.15)
				(type solid)
			)
			(layer "B.Fab")
		)
		(fp_line
			(start 0.504 0.25)
			(end -0.494 0.25)
			(stroke
				(width 0.15)
				(type solid)
			)
			(layer "B.Fab")
		)
		(fp_line
			(start -0.494 -0.248)
			(end 0.504 -0.248)
			(stroke
				(width 0.15)
				(type solid)
			)
			(layer "B.Fab")
		)
		(fp_line
			(start 0.504 -0.248)
			(end 0.504 0.25)
			(stroke
				(width 0.15)
				(type solid)
			)
			(layer "B.Fab")
		)
		(pad "1" smd roundrect
			(at -0.48 0 270)
			(size 0.59 0.64)
			(layers "B.Cu" "B.Mask" "B.Paste")
			(roundrect_rratio 0.25)
			(net 1 "GND")
			(pintype "passive")
			(teardrops
				(best_length_ratio 0.2)
				(max_length 1)
				(best_width_ratio 0.9)
				(max_width 2)
				(curved_edges yes)
				(filter_ratio 0.9)
				(enabled yes)
				(allow_two_segments yes)
				(prefer_zone_connections yes)
			)
		)
		(pad "2" smd roundrect
			(at 0.48 0 270)
			(size 0.59 0.64)
			(layers "B.Cu" "B.Mask" "B.Paste")
			(roundrect_rratio 0.25)
			(net 64 "Net-(U19-V_{CC})")
			(pintype "passive")
			(teardrops
				(best_length_ratio 0.2)
				(max_length 1)
				(best_width_ratio 0.9)
				(max_width 2)
				(curved_edges yes)
				(filter_ratio 0.9)
				(enabled yes)
				(allow_two_segments yes)
				(prefer_zone_connections yes)
			)
		)
	)
)
